(kicad_pcb
	(version 20241229)
	(generator "pcbnew")
	(generator_version "9.0")
	(general
		(thickness 1.61)
		(legacy_teardrops no)
	)
	(paper "A3")
	(title_block
		(title "RDIMM DDR5 Tester")
		(date "2026-05-21")
		(rev "2.2.0")
		(company "Antmicro")
		(comment 9 "footprints 553-557 of 796")
	)
	(layers
		(0 "F.Cu" signal)
		(4 "In1.Cu" power)
		(6 "In2.Cu" mixed)
		(8 "In3.Cu" power)
		(10 "In4.Cu" mixed)
		(12 "In5.Cu" power)
		(14 "In6.Cu" mixed)
		(16 "In7.Cu" power)
		(18 "In8.Cu" power)
		(20 "In9.Cu" mixed)
		(22 "In10.Cu" power)
		(2 "B.Cu" signal)
		(9 "F.Adhes" user "F.Adhesive")
		(11 "B.Adhes" user "B.Adhesive")
		(13 "F.Paste" user)
		(15 "B.Paste" user)
		(5 "F.SilkS" user "F.Silkscreen")
		(7 "B.SilkS" user "B.Silkscreen")
		(1 "F.Mask" user)
		(3 "B.Mask" user)
		(17 "Dwgs.User" user "User.Drawings")
		(19 "Cmts.User" user "User.Comments")
		(21 "Eco1.User" user "User.Eco1")
		(23 "Eco2.User" user "User.Eco2")
		(25 "Edge.Cuts" user)
		(27 "Margin" user)
		(31 "F.CrtYd" user "F.Courtyard")
		(29 "B.CrtYd" user "B.Courtyard")
		(35 "F.Fab" user)
		(33 "B.Fab" user)
	)
	(footprint "antmicro-footprints:R_0402_1005Metric"
		(layer "B.Cu")
		(at 221.03 183.97)
		(descr "Resistor SMD 0402")
		(tags "resistor SMD 0402")
		(property "Reference" "R197"
			(at -3.83 0.505 0)
			(layer "B.SilkS")
			(effects
				(font
					(size 0.7 0.7)
					(thickness 0.15)
				)
				(justify right bottom mirror)
			)
		)
		(property "Value" "R_4k99_0402"
			(at -1.011843 -1.772047 0)
			(layer "B.Fab")
			(effects
				(font
					(size 0.7 0.7)
					(thickness 0.15)
				)
				(justify right bottom mirror)
			)
		)
		(property "Datasheet" "https://www.bourns.com/docs/product-datasheets/cr.pdf"
			(at 0 0 0)
			(layer "F.Fab")
			(hide yes)
			(effects
				(font
					(size 1.27 1.27)
					(thickness 0.15)
				)
			)
		)
		(property "MPN" "CR0402-FX-4991GLF"
			(at 0 0 0)
			(unlocked yes)
			(layer "B.Fab")
			(hide yes)
			(effects
				(font
					(size 1 1)
					(thickness 0.15)
				)
				(justify mirror)
			)
		)
		(property "Manufacturer" "Bourns"
			(at 0 0 0)
			(unlocked yes)
			(layer "B.Fab")
			(hide yes)
			(effects
				(font
					(size 1 1)
					(thickness 0.15)
				)
				(justify mirror)
			)
		)
		(property "License" "Apache-2.0"
			(at 0 0 0)
			(unlocked yes)
			(layer "B.Fab")
			(hide yes)
			(effects
				(font
					(size 1 1)
					(thickness 0.15)
				)
				(justify mirror)
			)
		)
		(property "Author" "Antmicro"
			(at 0 0 0)
			(unlocked yes)
			(layer "B.Fab")
			(hide yes)
			(effects
				(font
					(size 1 1)
					(thickness 0.15)
				)
				(justify mirror)
			)
		)
		(property "Val" "4k99"
			(at 0 0 0)
			(unlocked yes)
			(layer "B.Fab")
			(hide yes)
			(effects
				(font
					(size 1 1)
					(thickness 0.15)
				)
				(justify mirror)
			)
		)
		(property "Tolerance" "1%"
			(at 0 0 0)
			(unlocked yes)
			(layer "B.Fab")
			(hide yes)
			(effects
				(font
					(size 1 1)
					(thickness 0.15)
				)
				(justify mirror)
			)
		)
		(sheetname "/Supply/DC-DC VCCINT/")
		(sheetfile "dc-dc-vccint.kicad_sch")
		(attr smd)
		(fp_rect
			(start -0.925 0.47)
			(end 0.925 -0.47)
			(stroke
				(width 0.05)
				(type default)
			)
			(fill no)
			(layer "B.CrtYd")
		)
		(fp_rect
			(start -0.5 0.25)
			(end 0.5 -0.25)
			(stroke
				(width 0.15)
				(type solid)
			)
			(fill no)
			(layer "B.Fab")
		)
		(fp_text user "Author: Antmicro"
			(at -0.95 -4.169 180)
			(layer "B.Fab")
			(effects
				(font
					(size 0.7 0.7)
					(thickness 0.15)
				)
				(justify left bottom mirror)
			)
		)
		(fp_text user "License: Apache-2.0"
			(at -0.95 -5.169 180)
			(layer "B.Fab")
			(effects
				(font
					(size 0.7 0.7)
					(thickness 0.15)
				)
				(justify left bottom mirror)
			)
		)
		(fp_text user "${REFERENCE}"
			(at -0.95 -3.168 180)
			(layer "B.Fab")
			(effects
				(font
					(size 0.7 0.7)
					(thickness 0.15)
				)
				(justify left bottom mirror)
			)
		)
		(pad "1" smd roundrect
			(at -0.48 0)
			(size 0.59 0.64)
			(layers "B.Cu" "B.Mask" "B.Paste")
			(roundrect_rratio 0.25)
			(net 1 "GND")
			(pintype "passive")
		)
		(pad "2" smd roundrect
			(at 0.48 0)
			(size 0.59 0.64)
			(layers "B.Cu" "B.Mask" "B.Paste")
			(roundrect_rratio 0.25)
			(net 727 "Net-(U4-ADDR)")
			(pintype "passive")
		)
	)
	(footprint "antmicro-footprints:C_0402_1005Metric_EIA"
		(layer "B.Cu")
		(at 186 162.5 90)
		(descr "Capacitor SMD 0402 (1005 Metric), square (rectangular) end terminal, IPC_7351 nominal, (Body size source: IPC-SM-782 page 76, https://www.pcb-3d.com/wordpress/wp-content/uploads/ipc-sm-782a_amendment_1_and_2.pdf)")
		(tags "capacitor 0402")
		(property "Reference" "C107"
			(at -3.95 0.1 90)
			(layer "B.SilkS")
			(effects
				(font
					(size 0.7 0.7)
					(thickness 0.15)
				)
				(justify right bottom mirror)
			)
		)
		(property "Value" "C_100n_0402"
			(at 0 -1.169 90)
			(layer "B.Fab")
			(effects
				(font
					(size 0.7 0.7)
					(thickness 0.15)
				)
				(justify right bottom mirror)
			)
		)
		(property "Datasheet" "https://www.murata.com/products/productdetail?partno=GRM155R61H104KE14%23"
			(at 0 0 90)
			(layer "F.Fab")
			(hide yes)
			(effects
				(font
					(size 1.27 1.27)
					(thickness 0.15)
				)
			)
		)
		(property "MPN" "GRM155R61H104KE14D"
			(at 0 0 90)
			(unlocked yes)
			(layer "B.Fab")
			(hide yes)
			(effects
				(font
					(size 1 1)
					(thickness 0.15)
				)
				(justify mirror)
			)
		)
		(property "Manufacturer" "Murata"
			(at 0 0 90)
			(unlocked yes)
			(layer "B.Fab")
			(hide yes)
			(effects
				(font
					(size 1 1)
					(thickness 0.15)
				)
				(justify mirror)
			)
		)
		(property "License" "Apache-2.0"
			(at 0 0 90)
			(unlocked yes)
			(layer "B.Fab")
			(hide yes)
			(effects
				(font
					(size 1 1)
					(thickness 0.15)
				)
				(justify mirror)
			)
		)
		(property "Author" "Antmicro"
			(at 0 0 90)
			(unlocked yes)
			(layer "B.Fab")
			(hide yes)
			(effects
				(font
					(size 1 1)
					(thickness 0.15)
				)
				(justify mirror)
			)
		)
		(property "Val" "100n"
			(at 0 0 90)
			(unlocked yes)
			(layer "B.Fab")
			(hide yes)
			(effects
				(font
					(size 1 1)
					(thickness 0.15)
				)
				(justify mirror)
			)
		)
		(property "Voltage" "50V"
			(at 0 0 90)
			(unlocked yes)
			(layer "B.Fab")
			(hide yes)
			(effects
				(font
					(size 1 1)
					(thickness 0.15)
				)
				(justify mirror)
			)
		)
		(property "Dielectric" "X5R"
			(at 0 0 90)
			(unlocked yes)
			(layer "B.Fab")
			(hide yes)
			(effects
				(font
					(size 1 1)
					(thickness 0.15)
				)
				(justify mirror)
			)
		)
		(sheetname "/FPGA power/")
		(sheetfile "fpga-power.kicad_sch")
		(attr smd)
		(fp_rect
			(start -0.95 0.45)
			(end 0.95 -0.45)
			(stroke
				(width 0.05)
				(type default)
			)
			(fill no)
			(layer "B.CrtYd")
		)
		(fp_line
			(start 0.498 -0.248)
			(end -0.5 -0.248)
			(stroke
				(width 0.15)
				(type solid)
			)
			(layer "B.Fab")
		)
		(fp_line
			(start -0.5 -0.248)
			(end -0.5 0.25)
			(stroke
				(width 0.15)
				(type solid)
			)
			(layer "B.Fab")
		)
		(fp_line
			(start 0.498 0.25)
			(end 0.498 -0.248)
			(stroke
				(width 0.15)
				(type solid)
			)
			(layer "B.Fab")
		)
		(fp_line
			(start -0.5 0.25)
			(end 0.498 0.25)
			(stroke
				(width 0.15)
				(type solid)
			)
			(layer "B.Fab")
		)
		(fp_text user "Author: Antmicro"
			(at -0.9656 -5.569 270)
			(layer "B.Fab")
			(effects
				(font
					(size 0.7 0.7)
					(thickness 0.15)
				)
				(justify left bottom mirror)
			)
		)
		(fp_text user "License: Apache-2.0"
			(at -0.9656 -4.369 270)
			(layer "B.Fab")
			(effects
				(font
					(size 0.7 0.7)
					(thickness 0.15)
				)
				(justify left bottom mirror)
			)
		)
		(fp_text user "${REFERENCE}"
			(at -0.9656 -3.169 270)
			(layer "B.Fab")
			(effects
				(font
					(size 0.7 0.7)
					(thickness 0.15)
				)
				(justify left bottom mirror)
			)
		)
		(pad "1" smd roundrect
			(at -0.5 0)
			(size 0.6 0.6)
			(layers "B.Cu" "B.Mask" "B.Paste")
			(roundrect_rratio 0.25)
			(net 1 "GND")
			(pintype "passive")
		)
		(pad "2" smd roundrect
			(at 0.498 0 90)
			(size 0.6 0.6)
			(layers "B.Cu" "B.Mask" "B.Paste")
			(roundrect_rratio 0.25)
			(net 172 "+1V2_MGTAVTT")
			(pintype "passive")
		)
	)
	(footprint "antmicro-footprints:C_0603_1608Metric"
		(layer "B.Cu")
		(at 188.5 153.75 90)
		(descr "Capacitor SMD 0603")
		(tags "capacitor 0603")
		(property "Reference" "C62"
			(at 9.725 -30.7 90)
			(layer "B.SilkS")
			(effects
				(font
					(size 0.7 0.7)
					(thickness 0.15)
				)
				(justify right bottom mirror)
			)
		)
		(property "Value" "C_47u_0603"
			(at -1.42757 -1.770288 90)
			(layer "B.Fab")
			(effects
				(font
					(size 0.7 0.7)
					(thickness 0.15)
				)
				(justify right bottom mirror)
			)
		)
		(property "Datasheet" "https://www.murata.com/products/productdetail?partno=GRM188R60J476ME15%23"
			(at 0 0 90)
			(layer "F.Fab")
			(hide yes)
			(effects
				(font
					(size 1.27 1.27)
					(thickness 0.15)
				)
			)
		)
		(property "Manufacturer" "Murata"
			(at 0 0 90)
			(unlocked yes)
			(layer "B.Fab")
			(hide yes)
			(effects
				(font
					(size 1 1)
					(thickness 0.15)
				)
				(justify mirror)
			)
		)
		(property "MPN" "GRM188R60J476ME15D"
			(at 0 0 90)
			(unlocked yes)
			(layer "B.Fab")
			(hide yes)
			(effects
				(font
					(size 1 1)
					(thickness 0.15)
				)
				(justify mirror)
			)
		)
		(property "Val" "47u"
			(at 0 0 90)
			(unlocked yes)
			(layer "B.Fab")
			(hide yes)
			(effects
				(font
					(size 1 1)
					(thickness 0.15)
				)
				(justify mirror)
			)
		)
		(property "License" "Apache-2.0"
			(at 0 0 90)
			(unlocked yes)
			(layer "B.Fab")
			(hide yes)
			(effects
				(font
					(size 1 1)
					(thickness 0.15)
				)
				(justify mirror)
			)
		)
		(property "Author" "Antmicro"
			(at 0 0 90)
			(unlocked yes)
			(layer "B.Fab")
			(hide yes)
			(effects
				(font
					(size 1 1)
					(thickness 0.15)
				)
				(justify mirror)
			)
		)
		(property "Voltage" ""
			(at 0 0 90)
			(unlocked yes)
			(layer "B.Fab")
			(hide yes)
			(effects
				(font
					(size 1 1)
					(thickness 0.15)
				)
				(justify mirror)
			)
		)
		(property "Dielectric" ""
			(at 0 0 90)
			(unlocked yes)
			(layer "B.Fab")
			(hide yes)
			(effects
				(font
					(size 1 1)
					(thickness 0.15)
				)
				(justify mirror)
			)
		)
		(sheetname "/FPGA power/")
		(sheetfile "fpga-power.kicad_sch")
		(attr smd)
		(fp_line
			(start -0.15 -0.4)
			(end 0.15 -0.4)
			(stroke
				(width 0.15)
				(type solid)
			)
			(layer "B.SilkS")
		)
		(fp_line
			(start -0.15 0.4)
			(end 0.15 0.4)
			(stroke
				(width 0.15)
				(type solid)
			)
			(layer "B.SilkS")
		)
		(fp_rect
			(start -1.25 0.65)
			(end 1.25 -0.65)
			(stroke
				(width 0.05)
				(type solid)
			)
			(fill no)
			(layer "B.CrtYd")
		)
		(fp_rect
			(start -0.8 0.4)
			(end 0.8 -0.4)
			(stroke
				(width 0.15)
				(type solid)
			)
			(fill no)
			(layer "B.Fab")
		)
		(fp_text user "${REFERENCE}"
			(at -1.682 -3.895 270)
			(layer "B.Fab")
			(effects
				(font
					(size 0.7 0.7)
					(thickness 0.15)
				)
				(justify left bottom mirror)
			)
		)
		(fp_text user "License: Apache-2.0"
			(at -1.682 -5.895 270)
			(layer "B.Fab")
			(effects
				(font
					(size 0.7 0.7)
					(thickness 0.15)
				)
				(justify left bottom mirror)
			)
		)
		(fp_text user "Author: Antmicro"
			(at -1.682 -4.894 270)
			(layer "B.Fab")
			(effects
				(font
					(size 0.7 0.7)
					(thickness 0.15)
				)
				(justify left bottom mirror)
			)
		)
		(pad "1" smd roundrect
			(at -0.7 0 90)
			(size 0.8 1)
			(layers "B.Cu" "B.Mask" "B.Paste")
			(roundrect_rratio 0.2)
			(net 553 "+0V85")
			(pintype "passive")
		)
		(pad "2" smd roundrect
			(at 0.7 0 90)
			(size 0.8 1)
			(layers "B.Cu" "B.Mask" "B.Paste")
			(roundrect_rratio 0.2)
			(net 1 "GND")
			(pintype "passive")
		)
	)
	(footprint "antmicro-footprints:R_0402_1005Metric"
		(layer "B.Cu")
		(at 217.89 151.85 180)
		(descr "Resistor SMD 0402")
		(tags "resistor SMD 0402")
		(property "Reference" "R8"
			(at 1.16 -0.47 0)
			(layer "B.SilkS")
			(effects
				(font
					(size 0.7 0.7)
					(thickness 0.15)
				)
				(justify left bottom mirror)
			)
		)
		(property "Value" "R_22R_0402"
			(at -1.011843 -1.772047 0)
			(layer "B.Fab")
			(effects
				(font
					(size 0.7 0.7)
					(thickness 0.15)
				)
				(justify left bottom mirror)
			)
		)
		(property "Datasheet" "https://www.bourns.com/docs/product-datasheets/cr.pdf"
			(at 0 0 180)
			(layer "F.Fab")
			(hide yes)
			(effects
				(font
					(size 1.27 1.27)
					(thickness 0.15)
				)
			)
		)
		(property "Manufacturer" "Bourns"
			(at 0 0 180)
			(unlocked yes)
			(layer "B.Fab")
			(hide yes)
			(effects
				(font
					(size 1 1)
					(thickness 0.15)
				)
				(justify mirror)
			)
		)
		(property "MPN" "CR0402-FX-22R0GLF"
			(at 0 0 180)
			(unlocked yes)
			(layer "B.Fab")
			(hide yes)
			(effects
				(font
					(size 1 1)
					(thickness 0.15)
				)
				(justify mirror)
			)
		)
		(property "Val" "22R"
			(at 0 0 180)
			(unlocked yes)
			(layer "B.Fab")
			(hide yes)
			(effects
				(font
					(size 1 1)
					(thickness 0.15)
				)
				(justify mirror)
			)
		)
		(property "License" "Apache-2.0"
			(at 0 0 180)
			(unlocked yes)
			(layer "B.Fab")
			(hide yes)
			(effects
				(font
					(size 1 1)
					(thickness 0.15)
				)
				(justify mirror)
			)
		)
		(property "Author" "Antmicro"
			(at 0 0 180)
			(unlocked yes)
			(layer "B.Fab")
			(hide yes)
			(effects
				(font
					(size 1 1)
					(thickness 0.15)
				)
				(justify mirror)
			)
		)
		(property "Tolerance" "1%"
			(at 0 0 180)
			(unlocked yes)
			(layer "B.Fab")
			(hide yes)
			(effects
				(font
					(size 1 1)
					(thickness 0.15)
				)
				(justify mirror)
			)
		)
		(sheetname "/HyperRAM + QSPI Flash/")
		(sheetfile "hyperram-flash.kicad_sch")
		(attr smd)
		(fp_rect
			(start -0.925 0.47)
			(end 0.925 -0.47)
			(stroke
				(width 0.05)
				(type default)
			)
			(fill no)
			(layer "B.CrtYd")
		)
		(fp_rect
			(start -0.5 0.25)
			(end 0.5 -0.25)
			(stroke
				(width 0.15)
				(type solid)
			)
			(fill no)
			(layer "B.Fab")
		)
		(fp_text user "${REFERENCE}"
			(at -0.95 -3.168 0)
			(layer "B.Fab")
			(effects
				(font
					(size 0.7 0.7)
					(thickness 0.15)
				)
				(justify left bottom mirror)
			)
		)
		(fp_text user "Author: Antmicro"
			(at -0.95 -4.169 0)
			(layer "B.Fab")
			(effects
				(font
					(size 0.7 0.7)
					(thickness 0.15)
				)
				(justify left bottom mirror)
			)
		)
		(fp_text user "License: Apache-2.0"
			(at -0.95 -5.169 0)
			(layer "B.Fab")
			(effects
				(font
					(size 0.7 0.7)
					(thickness 0.15)
				)
				(justify left bottom mirror)
			)
		)
		(pad "1" smd roundrect
			(at -0.48 0 180)
			(size 0.59 0.64)
			(layers "B.Cu" "B.Mask" "B.Paste")
			(roundrect_rratio 0.25)
			(net 280 "/HyperRAM + QSPI Flash/IO2")
			(pintype "passive")
		)
		(pad "2" smd roundrect
			(at 0.48 0 180)
			(size 0.59 0.64)
			(layers "B.Cu" "B.Mask" "B.Paste")
			(roundrect_rratio 0.25)
			(net 353 "/FPGA Config/FLASH.IO2")
			(pintype "passive")
		)
	)
	(footprint "antmicro-footprints:R_0402_1005Metric_EIA"
		(layer "B.Cu")
		(at 197.5 154)
		(descr "Resistor SMD 0402 (1005 Metric), square (rectangular) end terminal, IPC_7351 nominal, (Body size source: IPC-SM-782 page 76, https://www.pcb-3d.com/wordpress/wp-content/uploads/ipc-sm-782a_amendment_1_and_2.pdf)")
		(tags "resistor 0402")
		(property "Reference" "R194"
			(at -31.925 -10.3 0)
			(layer "B.SilkS")
			(effects
				(font
					(size 0.7 0.7)
					(thickness 0.15)
				)
				(justify right bottom mirror)
			)
		)
		(property "Value" "R_100R_0402"
			(at 0 -1.169 0)
			(layer "B.Fab")
			(effects
				(font
					(size 0.7 0.7)
					(thickness 0.15)
				)
				(justify right bottom mirror)
			)
		)
		(property "Datasheet" "https://www.bourns.com/docs/product-datasheets/cr.pdf"
			(at 0 0 0)
			(layer "F.Fab")
			(hide yes)
			(effects
				(font
					(size 1.27 1.27)
					(thickness 0.15)
				)
			)
		)
		(property "Manufacturer" "Bourns"
			(at 0 0 0)
			(unlocked yes)
			(layer "B.Fab")
			(hide yes)
			(effects
				(font
					(size 1 1)
					(thickness 0.15)
				)
				(justify mirror)
			)
		)
		(property "MPN" "CR0402-FX-1000GLF"
			(at 0 0 0)
			(unlocked yes)
			(layer "B.Fab")
			(hide yes)
			(effects
				(font
					(size 1 1)
					(thickness 0.15)
				)
				(justify mirror)
			)
		)
		(property "Val" "100R"
			(at 0 0 0)
			(unlocked yes)
			(layer "B.Fab")
			(hide yes)
			(effects
				(font
					(size 1 1)
					(thickness 0.15)
				)
				(justify mirror)
			)
		)
		(property "License" "Apache-2.0"
			(at 0 0 0)
			(unlocked yes)
			(layer "B.Fab")
			(hide yes)
			(effects
				(font
					(size 1 1)
					(thickness 0.15)
				)
				(justify mirror)
			)
		)
		(property "Author" "Antmicro"
			(at 0 0 0)
			(unlocked yes)
			(layer "B.Fab")
			(hide yes)
			(effects
				(font
					(size 1 1)
					(thickness 0.15)
				)
				(justify mirror)
			)
		)
		(property "Tolerance" "1%"
			(at 0 0 0)
			(unlocked yes)
			(layer "B.Fab")
			(hide yes)
			(effects
				(font
					(size 1 1)
					(thickness 0.15)
				)
				(justify mirror)
			)
		)
		(sheetname "/FPGA Config/")
		(sheetfile "fpga-config.kicad_sch")
		(attr smd)
		(fp_rect
			(start -0.95 0.45)
			(end 0.95 -0.45)
			(stroke
				(width 0.05)
				(type default)
			)
			(fill no)
			(layer "B.CrtYd")
		)
		(fp_line
			(start -0.5 -0.249)
			(end -0.5 0.25)
			(stroke
				(width 0.15)
				(type solid)
			)
			(layer "B.Fab")
		)
		(fp_line
			(start -0.5 0.25)
			(end 0.499 0.25)
			(stroke
				(width 0.15)
				(type solid)
			)
			(layer "B.Fab")
		)
		(fp_line
			(start 0.499 -0.249)
			(end -0.5 -0.249)
			(stroke
				(width 0.15)
				(type solid)
			)
			(layer "B.Fab")
		)
		(fp_line
			(start 0.499 0.25)
			(end 0.499 -0.249)
			(stroke
				(width 0.15)
				(type solid)
			)
			(layer "B.Fab")
		)
		(fp_text user "${REFERENCE}"
			(at -0.95 -3.169 180)
			(layer "B.Fab")
			(effects
				(font
					(size 0.7 0.7)
					(thickness 0.15)
				)
				(justify left bottom mirror)
			)
		)
		(fp_text user "Author: Antmicro"
			(at -0.95 -5.569 180)
			(layer "B.Fab")
			(effects
				(font
					(size 0.7 0.7)
					(thickness 0.15)
				)
				(justify left bottom mirror)
			)
		)
		(fp_text user "License: Apache-2.0"
			(at -0.95 -4.369 180)
			(layer "B.Fab")
			(effects
				(font
					(size 0.7 0.7)
					(thickness 0.15)
				)
				(justify left bottom mirror)
			)
		)
		(pad "1" smd roundrect
			(at -0.5 0 270)
			(size 0.6 0.6)
			(layers "B.Cu" "B.Mask" "B.Paste")
			(roundrect_rratio 0.25)
			(net 462 "/FPGA Config/POR_OVERRIDE")
			(pintype "passive")
		)
		(pad "2" smd roundrect
			(at 0.499 0)
			(size 0.6 0.6)
			(layers "B.Cu" "B.Mask" "B.Paste")
			(roundrect_rratio 0.25)
			(net 1 "GND")
			(pintype "passive")
		)
	)
)
